# T6G (Grand Teton) — schematic netlist excerpt (pin names and nets, part order shuffled) for the footprints in the layout excerpt that follows; sources: Cadence DE-HDL packaged netlist, KiCad conversion of 04192023_DAF0TMB3IC0_F0TG_MB_C_brd_V02_OCP.brd

PC422_5  Q_CAP  0.1UF 25V 10% X7R  pkg 0402  page 220 : A = PVDDCR_CPU1_P1_VCCS ; B = GND
PC6606  Q_CAP  10UF 6.3V 20% X6S  pkg C0402  page 362 : A = PV09_RETIMER_CPU0_VCCS ; B = GND

(kicad_pcb
	(version 20260206)
	(generator "pcbnew")
	(generator_version "10.0")
	(general
		(thickness 1.6)
		(legacy_teardrops no)
	)
	(paper "A4")
	(title_block
		(title "04192023_DAF0TMB3IC0_F0TG_MB_C_brd_V02_OCP.brd")
		(comment 1 "Grand Teton / footprints 1384-1385 of 8354")
	)
	(layers
		(0 "F.Cu" signal "TOP")
		(4 "In1.Cu" signal "GND")
		(6 "In2.Cu" signal "IN1")
		(8 "In3.Cu" signal "GND1")
		(10 "In4.Cu" signal "IN2")
		(12 "In5.Cu" signal "GND2")
		(14 "In6.Cu" signal "IN3")
		(16 "In7.Cu" signal "GND3")
		(18 "In8.Cu" signal "VCC")
		(20 "In9.Cu" signal "VCC1")
		(22 "In10.Cu" signal "GND4")
		(24 "In11.Cu" signal "IN4")
		(26 "In12.Cu" signal "GND5")
		(28 "In13.Cu" signal "IN5")
		(30 "In14.Cu" signal "GND6")
		(32 "In15.Cu" signal "IN6")
		(34 "In16.Cu" signal "GND7")
		(2 "B.Cu" signal "BOTTOM")
		(9 "F.Adhes" user "F.Adhesive")
		(11 "B.Adhes" user "B.Adhesive")
		(13 "F.Paste" user "Package Geometry/Pastemask Top")
		(15 "B.Paste" user "Package Geometry/Pastemask Bottom")
		(5 "F.SilkS" user "Ref Des/Silkscreen Top")
		(7 "B.SilkS" user "Ref Des/Silkscreen Bottom")
		(1 "F.Mask" user "Board Geometry/Soldermask Top")
		(3 "B.Mask" user "Board Geometry/Soldermask Bottom")
		(17 "Dwgs.User" user "User.Drawings")
		(19 "Cmts.User" user "User.Comments")
		(21 "Eco1.User" user "User.Eco1")
		(23 "Eco2.User" user "User.Eco2")
		(25 "Edge.Cuts" user "Board Geometry/Outline")
		(27 "Margin" user)
		(31 "F.CrtYd" user "Package Geometry/Place Bound Top")
		(29 "B.CrtYd" user "Package Geometry/Place Bound Bottom")
		(35 "F.Fab" user "Ref Des/Assembly Top")
		(33 "B.Fab" user "Ref Des/Assembly Bottom")
	)
	(footprint ""
		(layer "F.Cu")
		(at 92.75953 -339.886798 90)
		(property "Reference" "PC422_5"
			(at 0 0 90)
			(layer "F.SilkS")
			(hide yes)
			(effects
				(font
					(size 1.27 1.27)
				)
			)
		)
		(property "Value" ""
			(at 0 0 90)
			(layer "F.Fab")
			(effects
				(font
					(size 1.27 1.27)
				)
			)
		)
		(duplicate_pad_numbers_are_jumpers no)
		(fp_line
			(start 0.7874 -0.4064)
			(end 0.7874 0.4064)
			(stroke
				(width 0.1524)
				(type default)
			)
			(layer "F.SilkS")
		)
		(fp_line
			(start -0.7874 -0.4064)
			(end 0.7874 -0.4064)
			(stroke
				(width 0.1524)
				(type default)
			)
			(layer "F.SilkS")
		)
		(fp_line
			(start 0.7874 0.4064)
			(end -0.7874 0.4064)
			(stroke
				(width 0.1524)
				(type default)
			)
			(layer "F.SilkS")
		)
		(fp_line
			(start -0.7874 0.4064)
			(end -0.7874 -0.4064)
			(stroke
				(width 0.1524)
				(type default)
			)
			(layer "F.SilkS")
		)
		(fp_line
			(start -0.12065 -0.305054)
			(end -0.12065 -0.2794)
			(stroke
				(width 0.1)
				(type default)
			)
			(layer "F.Fab")
		)
		(fp_line
			(start -0.67945 -0.305054)
			(end -0.12065 -0.305054)
			(stroke
				(width 0.1)
				(type default)
			)
			(layer "F.Fab")
		)
		(fp_line
			(start 0.67945 -0.3048)
			(end 0.67945 0.3048)
			(stroke
				(width 0.1)
				(type default)
			)
			(layer "F.Fab")
		)
		(fp_line
			(start 0.12065 -0.3048)
			(end 0.67945 -0.3048)
			(stroke
				(width 0.1)
				(type default)
			)
			(layer "F.Fab")
		)
		(fp_line
			(start 0.12065 -0.2794)
			(end 0.12065 -0.3048)
			(stroke
				(width 0.1)
				(type default)
			)
			(layer "F.Fab")
		)
		(fp_line
			(start -0.12065 -0.2794)
			(end 0.12065 -0.2794)
			(stroke
				(width 0.1)
				(type default)
			)
			(layer "F.Fab")
		)
		(fp_line
			(start 0.120396 0.2794)
			(end -0.12065 0.2794)
			(stroke
				(width 0.1)
				(type default)
			)
			(layer "F.Fab")
		)
		(fp_line
			(start -0.12065 0.2794)
			(end -0.12065 0.3048)
			(stroke
				(width 0.1)
				(type default)
			)
			(layer "F.Fab")
		)
		(fp_line
			(start 0.67945 0.3048)
			(end 0.120396 0.3048)
			(stroke
				(width 0.1)
				(type default)
			)
			(layer "F.Fab")
		)
		(fp_line
			(start 0.120396 0.3048)
			(end 0.120396 0.2794)
			(stroke
				(width 0.1)
				(type default)
			)
			(layer "F.Fab")
		)
		(fp_line
			(start -0.12065 0.3048)
			(end -0.67945 0.3048)
			(stroke
				(width 0.1)
				(type default)
			)
			(layer "F.Fab")
		)
		(fp_line
			(start -0.67945 0.3048)
			(end -0.67945 -0.305054)
			(stroke
				(width 0.1)
				(type default)
			)
			(layer "F.Fab")
		)
		(pad "1" smd circle
			(at -0.40005 0 90)
			(size 0 0)
			(layers "F.Cu" "F.Mask" "F.Paste")
			(net "PVDDCR_CPU1_P1_VCCS")
		)
		(pad "2" smd circle
			(at 0.40005 0 90)
			(size 0 0)
			(layers "F.Cu" "F.Mask" "F.Paste")
			(net "GND")
		)
	)
	(footprint ""
		(layer "F.Cu")
		(at 446.776602 -428.61611 90)
		(property "Reference" "PC6606"
			(at 0 0 90)
			(layer "F.SilkS")
			(hide yes)
			(effects
				(font
					(size 1.27 1.27)
				)
			)
		)
		(property "Value" ""
			(at 0 0 90)
			(layer "F.Fab")
			(effects
				(font
					(size 1.27 1.27)
				)
			)
		)
		(duplicate_pad_numbers_are_jumpers no)
		(fp_line
			(start 0.7874 -0.4064)
			(end 0.7874 0.4064)
			(stroke
				(width 0.1524)
				(type default)
			)
			(layer "F.SilkS")
		)
		(fp_line
			(start -0.7874 -0.4064)
			(end 0.7874 -0.4064)
			(stroke
				(width 0.1524)
				(type default)
			)
			(layer "F.SilkS")
		)
		(fp_line
			(start 0.7874 0.4064)
			(end -0.7874 0.4064)
			(stroke
				(width 0.1524)
				(type default)
			)
			(layer "F.SilkS")
		)
		(fp_line
			(start -0.7874 0.4064)
			(end -0.7874 -0.4064)
			(stroke
				(width 0.1524)
				(type default)
			)
			(layer "F.SilkS")
		)
		(fp_line
			(start -0.12065 -0.305054)
			(end -0.12065 -0.2794)
			(stroke
				(width 0.1)
				(type default)
			)
			(layer "F.Fab")
		)
		(fp_line
			(start -0.67945 -0.305054)
			(end -0.12065 -0.305054)
			(stroke
				(width 0.1)
				(type default)
			)
			(layer "F.Fab")
		)
		(fp_line
			(start 0.67945 -0.3048)
			(end 0.67945 0.3048)
			(stroke
				(width 0.1)
				(type default)
			)
			(layer "F.Fab")
		)
		(fp_line
			(start 0.12065 -0.3048)
			(end 0.67945 -0.3048)
			(stroke
				(width 0.1)
				(type default)
			)
			(layer "F.Fab")
		)
		(fp_line
			(start 0.12065 -0.2794)
			(end 0.12065 -0.3048)
			(stroke
				(width 0.1)
				(type default)
			)
			(layer "F.Fab")
		)
		(fp_line
			(start -0.12065 -0.2794)
			(end 0.12065 -0.2794)
			(stroke
				(width 0.1)
				(type default)
			)
			(layer "F.Fab")
		)
		(fp_line
			(start 0.120396 0.2794)
			(end -0.12065 0.2794)
			(stroke
				(width 0.1)
				(type default)
			)
			(layer "F.Fab")
		)
		(fp_line
			(start -0.12065 0.2794)
			(end -0.12065 0.3048)
			(stroke
				(width 0.1)
				(type default)
			)
			(layer "F.Fab")
		)
		(fp_line
			(start 0.67945 0.3048)
			(end 0.120396 0.3048)
			(stroke
				(width 0.1)
				(type default)
			)
			(layer "F.Fab")
		)
		(fp_line
			(start 0.120396 0.3048)
			(end 0.120396 0.2794)
			(stroke
				(width 0.1)
				(type default)
			)
			(layer "F.Fab")
		)
		(fp_line
			(start -0.12065 0.3048)
			(end -0.67945 0.3048)
			(stroke
				(width 0.1)
				(type default)
			)
			(layer "F.Fab")
		)
		(fp_line
			(start -0.67945 0.3048)
			(end -0.67945 -0.305054)
			(stroke
				(width 0.1)
				(type default)
			)
			(layer "F.Fab")
		)
		(pad "1" smd circle
			(at -0.40005 0 90)
			(size 0 0)
			(layers "F.Cu" "F.Mask" "F.Paste")
			(net "PV09_RETIMER_CPU0_VCCS")
		)
		(pad "2" smd circle
			(at 0.40005 0 90)
			(size 0 0)
			(layers "F.Cu" "F.Mask" "F.Paste")
			(net "GND")
		)
	)
)
